# T6G (Grand Teton) — schematic netlist excerpt (pin names and nets, part order shuffled) for the footprints in the layout excerpt that follows; sources: Cadence DE-HDL packaged netlist, KiCad conversion of 04192023_DAF0TMB3IC0_F0TG_MB_C_brd_V02_OCP.brd

J29  SCONN288_DDR506112002KQ  IO  pkg DDR288S_1-1VXC  page 107
  VIN_BULK0  = P12V_MEM_CPU1
  RFU0  = NC
  VIN_MGMT  = P3V3_AUX
  HSCL  = I3C_SPD_DDRJ_CPU1_SCL
  HSDA  = I3C_SPD_DDRJ_CPU1_SDA
  VSS0  = GND
  DQ0_A  = M_J_CPU1_SA_DQ<0>
  VSS1  = GND
  DQ1_A  = M_J_CPU1_SA_DQ<1>
  VSS2  = GND
  DQS0_A_T  = M_J_CPU1_SA_DQS_DP<0>
  DQS0_A_C  = M_J_CPU1_SA_DQS_DN<0>
  VSS3  = GND
  DQ4_A  = M_J_CPU1_SA_DQ<4>
  VSS4  = GND
  DQ5_A  = M_J_CPU1_SA_DQ<5>
  VSS5  = GND
  DQ8_A  = M_J_CPU1_SA_DQ<8>
  VSS6  = GND
  DQ9_A  = M_J_CPU1_SA_DQ<9>
  VSS7  = GND
  DQS1_A_T  = M_J_CPU1_SA_DQS_DP<1>
  DQS1_A_C  = M_J_CPU1_SA_DQS_DN<1>
  VSS8  = GND
  DQ12_A  = M_J_CPU1_SA_DQ<12>
  VSS9  = GND
  DQ13_A  = M_J_CPU1_SA_DQ<13>
  VSS10  = GND
  DQ16_A  = M_J_CPU1_SA_DQ<16>
  VSS11  = GND
  DQ17_A  = M_J_CPU1_SA_DQ<17>
  VSS12  = GND
  DQS2_A_T  = M_J_CPU1_SA_DQS_DP<2>
  DQS2_A_C  = M_J_CPU1_SA_DQS_DN<2>
  VSS13  = GND
  DQ20_A  = M_J_CPU1_SA_DQ<20>
  VSS14  = GND
  DQ21_A  = M_J_CPU1_SA_DQ<21>
  VSS15  = GND
  DQ24_A  = M_J_CPU1_SA_DQ<24>
  VSS16  = GND
  DQ25_A  = M_J_CPU1_SA_DQ<25>
  VSS17  = GND
  DQS3_A_T  = M_J_CPU1_SA_DQS_DP<3>
  DQS3_A_C  = M_J_CPU1_SA_DQS_DN<3>
  VSS18  = GND
  DQ28_A  = M_J_CPU1_SA_DQ<28>
  VSS19  = GND
  DQ29_A  = M_J_CPU1_SA_DQ<29>
  VSS20  = GND
  CB0_A  = M_J_CPU1_SA_CB<0>
  VSS21  = GND
  CB1_A  = M_J_CPU1_SA_CB<1>
  VSS22  = GND
  DQS4_A_T  = M_J_CPU1_SA_DQS_DP<4>
  DQS4_A_C  = M_J_CPU1_SA_DQS_DN<4>
  VSS23  = GND
  CB4_A  = M_J_CPU1_SA_CB<4>
  VSS24  = GND
  CB5_A  = M_J_CPU1_SA_CB<5>
  VSS25  = GND
  ALERT_N  = M_J_CPU1_ALERT_N
  VSS26  = GND
  CS0_A_N  = M_J_CPU1_SA_CS_N<0>
  VSS27  = GND
  CA0_A  = M_J_CPU1_SA_CA<0>
  VSS28  = GND
  CA2_A  = M_J_CPU1_SA_CA<2>
  VSS29  = GND
  CA4_A  = M_J_CPU1_SA_CA<4>
  VSS30  = GND
  CA6_A  = M_J_CPU1_SA_CA<6>
  VSS31  = GND
  PAR_A  = M_J_CPU1_SA_PAR
  VSS32  = GND
  CA0_B  = M_J_CPU1_SB_CA<0>
  VSS33  = GND
  CA2_B  = M_J_CPU1_SB_CA<2>
  VSS34  = GND
  CA4_B  = M_J_CPU1_SB_CA<4>
  VSS35  = GND
  CA6_B  = M_J_CPU1_SB_CA<6>
  VSS36  = GND
  CS0_B_N  = M_J_CPU1_SB_CS_N<0>
  VSS37  = GND
  \lbd||rsp_a_n\  = M_J_CPU1_SA_RSP<0>
  \lbs||rsp_b_n\  = M_J_CPU1_SB_RSP<0>
  VSS38  = GND
  CB4_B  = M_J_CPU1_SB_CB<4>
  VSS39  = GND
  CB5_B  = M_J_CPU1_SB_CB<5>
  VSS40  = GND
  \dqs9_b_t||tdqs9_b_t||dbi4_b_n\  = M_J_CPU1_SB_DQS_DP<9>
  \dqs9_b_c||tdqs9_b_c\  = M_J_CPU1_SB_DQS_DN<9>
  VSS41  = GND
  CB0_B  = M_J_CPU1_SB_CB<0>
  VSS42  = GND
  CB1_B  = M_J_CPU1_SB_CB<1>
  VSS43  = GND
  DQ0_B  = M_J_CPU1_SB_DQ<0>
  VSS44  = GND
  DQ1_B  = M_J_CPU1_SB_DQ<1>
  VSS45  = GND
  DQS0_B_T  = M_J_CPU1_SB_DQS_DP<0>
  DQS0_B_C  = M_J_CPU1_SB_DQS_DN<0>
  VSS46  = GND
  DQ4_B  = M_J_CPU1_SB_DQ<4>
  VSS47  = GND
  DQ5_B  = M_J_CPU1_SB_DQ<5>
  VSS48  = GND
  DQ8_B  = M_J_CPU1_SB_DQ<8>
  VSS49  = GND
  DQ9_B  = M_J_CPU1_SB_DQ<9>
  VSS50  = GND
  DQS1_B_T  = M_J_CPU1_SB_DQS_DP<1>
  DQS1_B_C  = M_J_CPU1_SB_DQS_DN<1>
  VSS51  = GND
  DQ12_B  = M_J_CPU1_SB_DQ<12>
  VSS52  = GND
  DQ13_B  = M_J_CPU1_SB_DQ<13>
  VSS53  = GND
  DQ16_B  = M_J_CPU1_SB_DQ<16>
  VSS54  = GND
  DQ17_B  = M_J_CPU1_SB_DQ<17>
  VSS55  = GND
  DQS2_B_T  = M_J_CPU1_SB_DQS_DP<2>
  DQS2_B_C  = M_J_CPU1_SB_DQS_DN<2>
  VSS56  = GND
  DQ20_B  = M_J_CPU1_SB_DQ<20>
  VSS57  = GND
  DQ21_B  = M_J_CPU1_SB_DQ<21>
  VSS58  = GND
  DQ24_B  = M_J_CPU1_SB_DQ<24>
  VSS59  = GND
  DQ25_B  = M_J_CPU1_SB_DQ<25>
  VSS60  = GND
  DQS3_B_T  = M_J_CPU1_SB_DQS_DP<3>
  DQS3_B_C  = M_J_CPU1_SB_DQS_DN<3>
  VSS61  = GND
  DQ28_B  = M_J_CPU1_SB_DQ<28>
  VSS62  = GND
  DQ29_B  = M_J_CPU1_SB_DQ<29>
  VSS63  = GND
  RFU1  = NC
  VIN_BULK1  = P12V_MEM_CPU1
  VIN_BULK2  = P12V_MEM_CPU1
  \pwr_good||fail_n\  = PWRGD_CHJ_CPU1_DIMM
  HAS  = PD_CHJ_CPU1_DIMM_SAA
  RFU2  = NC
  RFU3  = NC
  VSS64  = GND
  DQ2_A  = M_J_CPU1_SA_DQ<2>
  VSS65  = GND
  DQ3_A  = M_J_CPU1_SA_DQ<3>
  VSS66  = GND
  \dqs5_a_c||tdqs5_a_c||dqs5_a_t||tdqs5_a_t\  = M_J_CPU1_SA_DQS_DN<5>
  \dqs5_a_t||tdqs5_a_t\  = M_J_CPU1_SA_DQS_DP<5>
  VSS67  = GND
  DQ6_A  = M_J_CPU1_SA_DQ<6>
  VSS68  = GND
  DQ7_A  = M_J_CPU1_SA_DQ<7>
  VSS69  = GND
  DQ10_A  = M_J_CPU1_SA_DQ<10>
  VSS70  = GND
  DQ11_A  = M_J_CPU1_SA_DQ<11>
  VSS71  = GND
  \dqs6_a_c||tdqs6_a_c||dqs6_a_t||tdqs6_a_t\  = M_J_CPU1_SA_DQS_DN<6>
  \dqs6_a_t||tdqs6_a_t\  = M_J_CPU1_SA_DQS_DP<6>
  VSS72  = GND
  DQ14_A  = M_J_CPU1_SA_DQ<14>
  VSS73  = GND
  DQ15_A  = M_J_CPU1_SA_DQ<15>
  VSS74  = GND
  DQ18_A  = M_J_CPU1_SA_DQ<18>
  VSS75  = GND
  DQ19_A  = M_J_CPU1_SA_DQ<19>
  VSS76  = GND
  \dqs7_a_c||tdqs7_a_c\  = M_J_CPU1_SA_DQS_DN<7>
  \dqs7_a_t||tdqs7_a_t\  = M_J_CPU1_SA_DQS_DP<7>
  VSS77  = GND
  DQ22_A  = M_J_CPU1_SA_DQ<22>
  VSS78  = GND
  DQ23_A  = M_J_CPU1_SA_DQ<23>
  VSS79  = GND
  DQ26_A  = M_J_CPU1_SA_DQ<26>
  VSS80  = GND
  DQ27_A  = M_J_CPU1_SA_DQ<27>
  VSS81  = GND
  \dqs8_a_c||tdqs8_a_c\  = M_J_CPU1_SA_DQS_DN<8>
  \dqs8_a_t||tdqs8_a_t\  = M_J_CPU1_SA_DQS_DP<8>
  VSS82  = GND
  DQ30_A  = M_J_CPU1_SA_DQ<30>
  VSS83  = GND
  DQ31_A  = M_J_CPU1_SA_DQ<31>
  VSS84  = GND
  CB2_A  = M_J_CPU1_SA_CB<2>
  VSS85  = GND
  CB3_A  = M_J_CPU1_SA_CB<3>
  VSS86  = GND
  \dqs9_a_c||tdqs9_a_c\  = M_J_CPU1_SA_DQS_DN<9>
  \dqs9_a_t||tdqs9_a_t\  = M_J_CPU1_SA_DQS_DP<9>
  VSS87  = GND
  CB6_A  = M_J_CPU1_SA_CB<6>
  VSS88  = GND
  CB7_A  = M_J_CPU1_SA_CB<7>
  VSS89  = GND
  RESET_N  = M_J_CPU1_RESET_N
  VSS90  = GND
  CS1_A_N  = M_J_CPU1_SA_CS_N<1>
  VSS91  = GND
  CA1_A  = M_J_CPU1_SA_CA<1>
  VSS92  = GND
  CA3_A  = M_J_CPU1_SA_CA<3>
  VSS93  = GND
  CA5_A  = M_J_CPU1_SA_CA<5>
  VSS94  = GND
  CK_T  = M_J_CPU1_CLK_DP<0>
  CK_C  = M_J_CPU1_CLK_DN<0>
  VSS95  = GND
  RFU4  = NC
  CA1_B  = M_J_CPU1_SB_CA<1>
  VSS96  = GND
  CA3_B  = M_J_CPU1_SB_CA<3>
  VSS97  = GND
  CA5_B  = M_J_CPU1_SB_CA<5>
  VSS98  = GND
  PAR_B  = M_J_CPU1_SB_PAR
  VSS99  = GND
  CS1_B_N  = M_J_CPU1_SB_CS_N<1>
  VSS100  = GND
  RFU5  = NC
  RFU6  = NC
  VSS101  = GND
  CB6_B  = M_J_CPU1_SB_CB<6>
  VSS102  = GND
  CB7_B  = M_J_CPU1_SB_CB<7>
  VSS103  = GND
  DQS4_B_C  = M_J_CPU1_SB_DQS_DN<4>
  DQS4_B_T  = M_J_CPU1_SB_DQS_DP<4>
  VSS104  = GND
  CB2_B  = M_J_CPU1_SB_CB<2>
  VSS105  = GND
  CB3_B  = M_J_CPU1_SB_CB<3>
  VSS106  = GND
  DQ2_B  = M_J_CPU1_SB_DQ<2>
  VSS107  = GND
  DQ3_B  = M_J_CPU1_SB_DQ<3>
  VSS108  = GND
  \dqs5_b_c||tdqs5_b_c\  = M_J_CPU1_SB_DQS_DN<5>
  \dqs5_b_t||tdqs5_b_t\  = M_J_CPU1_SB_DQS_DP<5>
  VSS109  = GND
  DQ6_B  = M_J_CPU1_SB_DQ<6>
  VSS110  = GND
  DQ7_B  = M_J_CPU1_SB_DQ<7>
  VSS111  = GND
  DQ10_B  = M_J_CPU1_SB_DQ<10>
  VSS112  = GND
  DQ11_B  = M_J_CPU1_SB_DQ<11>
  VSS113  = GND
  \dqs6_b_c||tdqs6_b_c\  = M_J_CPU1_SB_DQS_DN<6>
  \dqs6_b_t||tdqs6_b_t\  = M_J_CPU1_SB_DQS_DP<6>
  VSS114  = GND
  DQ14_B  = M_J_CPU1_SB_DQ<14>
  VSS115  = GND
  DQ15_B  = M_J_CPU1_SB_DQ<15>
  VSS116  = GND
  DQ18_B  = M_J_CPU1_SB_DQ<18>
  VSS117  = GND
  DQ19_B  = M_J_CPU1_SB_DQ<19>
  VSS118  = GND
  \dqs7_b_c||tdqs7_b_c\  = M_J_CPU1_SB_DQS_DN<7>
  \dqs7_b_t||tdqs7_b_t\  = M_J_CPU1_SB_DQS_DP<7>
  VSS119  = GND
  DQ22_B  = M_J_CPU1_SB_DQ<22>
  VSS120  = GND
  DQ23_B  = M_J_CPU1_SB_DQ<23>
  VSS121  = GND
  DQ26_B  = M_J_CPU1_SB_DQ<26>
  VSS122  = GND
  DQ27_B  = M_J_CPU1_SB_DQ<27>
  VSS123  = GND
  \dqs8_b_c||tdqs8_b_c\  = M_J_CPU1_SB_DQS_DN<8>
  \dqs8_b_t||tdqs8_b_t\  = M_J_CPU1_SB_DQS_DP<8>
  VSS124  = GND
  DQ30_B  = M_J_CPU1_SB_DQ<30>
  VSS125  = GND
  DQ31_B  = M_J_CPU1_SB_DQ<31>
  VSS126  = GND
  G1  = GND
  G2  = GND
  G3  = GND

(kicad_pcb
	(version 20260206)
	(generator "pcbnew")
	(generator_version "10.0")
	(general
		(thickness 1.6)
		(legacy_teardrops no)
	)
	(paper "A4")
	(title_block
		(title "04192023_DAF0TMB3IC0_F0TG_MB_C_brd_V02_OCP.brd")
		(comment 1 "Grand Teton / footprint 1456 of 8354 (J29), pads 276-291 of 291")
	)
	(layers
		(0 "F.Cu" signal "TOP")
		(4 "In1.Cu" signal "GND")
		(6 "In2.Cu" signal "IN1")
		(8 "In3.Cu" signal "GND1")
		(10 "In4.Cu" signal "IN2")
		(12 "In5.Cu" signal "GND2")
		(14 "In6.Cu" signal "IN3")
		(16 "In7.Cu" signal "GND3")
		(18 "In8.Cu" signal "VCC")
		(20 "In9.Cu" signal "VCC1")
		(22 "In10.Cu" signal "GND4")
		(24 "In11.Cu" signal "IN4")
		(26 "In12.Cu" signal "GND5")
		(28 "In13.Cu" signal "IN5")
		(30 "In14.Cu" signal "GND6")
		(32 "In15.Cu" signal "IN6")
		(34 "In16.Cu" signal "GND7")
		(2 "B.Cu" signal "BOTTOM")
		(9 "F.Adhes" user "F.Adhesive")
		(11 "B.Adhes" user "B.Adhesive")
		(13 "F.Paste" user "Package Geometry/Pastemask Top")
		(15 "B.Paste" user "Package Geometry/Pastemask Bottom")
		(5 "F.SilkS" user "Ref Des/Silkscreen Top")
		(7 "B.SilkS" user "Ref Des/Silkscreen Bottom")
		(1 "F.Mask" user "Board Geometry/Soldermask Top")
		(3 "B.Mask" user "Board Geometry/Soldermask Bottom")
		(17 "Dwgs.User" user "User.Drawings")
		(19 "Cmts.User" user "User.Comments")
		(21 "Eco1.User" user "User.Eco1")
		(23 "Eco2.User" user "User.Eco2")
		(25 "Edge.Cuts" user "Board Geometry/Outline")
		(27 "Margin" user)
		(31 "F.CrtYd" user "Package Geometry/Place Bound Top")
		(29 "B.CrtYd" user "Package Geometry/Place Bound Bottom")
		(35 "F.Fab" user "Ref Des/Assembly Top")
		(33 "B.Fab" user "Ref Des/Assembly Bottom")
	)
	(footprint ""
		(layer "F.Cu")
		(at 189.110112 -255.560322 180)
		(property "Reference" "J29"
			(at -2.7178 -81.857088 0)
			(unlocked yes)
			(layer "F.SilkS")
			(effects
				(font
					(size 0.7874 0.5842)
					(thickness 0.1524)
				)
			)
		)
		(property "Value" ""
			(at 0 0 180)
			(layer "F.Fab")
			(effects
				(font
					(size 1.27 1.27)
				)
			)
		)
		(duplicate_pad_numbers_are_jumpers no)
		(pad "276" smd rect
			(at 2.050034 53.125116 90)
			(size 0.519938 1.4986)
			(layers "F.Cu" "F.Mask" "F.Paste")
			(net "M_J_CPU1_SB_DQ<23>")
		)
		(pad "277" smd rect
			(at 2.050034 53.975 90)
			(size 0.519938 1.4986)
			(layers "F.Cu" "F.Mask" "F.Paste")
			(net "GND")
		)
		(pad "278" smd rect
			(at 2.050034 54.824884 90)
			(size 0.519938 1.4986)
			(layers "F.Cu" "F.Mask" "F.Paste")
			(net "M_J_CPU1_SB_DQ<26>")
		)
		(pad "279" smd rect
			(at 2.050034 55.675022 90)
			(size 0.519938 1.4986)
			(layers "F.Cu" "F.Mask" "F.Paste")
			(net "GND")
		)
		(pad "280" smd rect
			(at 2.050034 56.524906 90)
			(size 0.519938 1.4986)
			(layers "F.Cu" "F.Mask" "F.Paste")
			(net "M_J_CPU1_SB_DQ<27>")
		)
		(pad "281" smd rect
			(at 2.050034 57.375044 90)
			(size 0.519938 1.4986)
			(layers "F.Cu" "F.Mask" "F.Paste")
			(net "GND")
		)
		(pad "282" smd rect
			(at 2.050034 58.224928 90)
			(size 0.519938 1.4986)
			(layers "F.Cu" "F.Mask" "F.Paste")
			(net "M_J_CPU1_SB_DQS_DN<8>")
		)
		(pad "283" smd rect
			(at 2.050034 59.075066 90)
			(size 0.519938 1.4986)
			(layers "F.Cu" "F.Mask" "F.Paste")
			(net "M_J_CPU1_SB_DQS_DP<8>")
		)
		(pad "284" smd rect
			(at 2.050034 59.92495 90)
			(size 0.519938 1.4986)
			(layers "F.Cu" "F.Mask" "F.Paste")
			(net "GND")
		)
		(pad "285" smd rect
			(at 2.050034 60.775088 90)
			(size 0.519938 1.4986)
			(layers "F.Cu" "F.Mask" "F.Paste")
			(net "M_J_CPU1_SB_DQ<30>")
		)
		(pad "286" smd rect
			(at 2.050034 61.624972 90)
			(size 0.519938 1.4986)
			(layers "F.Cu" "F.Mask" "F.Paste")
			(net "GND")
		)
		(pad "287" smd rect
			(at 2.050034 62.47511 90)
			(size 0.519938 1.4986)
			(layers "F.Cu" "F.Mask" "F.Paste")
			(net "M_J_CPU1_SB_DQ<31>")
		)
		(pad "288" smd rect
			(at 2.050034 63.324994 90)
			(size 0.519938 1.4986)
			(layers "F.Cu" "F.Mask" "F.Paste")
			(net "GND")
		)
		(pad "G1" thru_hole oval
			(at 0 -68.97497 90)
			(size 1.7272 3.4798)
			(drill oval 1.2192 2.4638)
			(layers "*.Cu" "*.Mask")
			(remove_unused_layers no)
			(net "GND")
			(clearance 0.127)
			(thermal_gap 0.127)
		)
		(pad "G2" thru_hole oval
			(at 0 3.875024 90)
			(size 1.7272 3.4798)
			(drill oval 1.2192 2.4638)
			(layers "*.Cu" "*.Mask")
			(remove_unused_layers no)
			(net "GND")
			(clearance 0.127)
			(thermal_gap 0.127)
		)
		(pad "G3" thru_hole oval
			(at 0 68.97497 90)
			(size 1.7272 3.4798)
			(drill oval 1.2192 2.4638)
			(layers "*.Cu" "*.Mask")
			(remove_unused_layers no)
			(net "GND")
			(clearance 0.127)
			(thermal_gap 0.127)
		)
	)
)
